(kicad_pcb
	(version 20241229)
	(generator "pcbnew")
	(generator_version "9.0")
	(general
		(thickness 1.711)
		(legacy_teardrops no)
	)
	(paper "A4")
	(title_block
		(title "Antmicro Baseboard for Jetson AGX Thor")
		(date "2026-02-18")
		(rev "1.1.0")
		(company "Antmicro Ltd")
		(comment 1 "www.antmicro.com")
		(comment 9 "footprints 467-470 of 1170")
	)
	(layers
		(0 "F.Cu" signal)
		(4 "In1.Cu" signal)
		(6 "In2.Cu" signal)
		(8 "In3.Cu" signal)
		(10 "In4.Cu" jumper)
		(12 "In5.Cu" signal)
		(14 "In6.Cu" signal)
		(16 "In7.Cu" signal)
		(18 "In8.Cu" signal)
		(2 "B.Cu" signal)
		(9 "F.Adhes" user "F.Adhesive")
		(11 "B.Adhes" user "B.Adhesive")
		(13 "F.Paste" user)
		(15 "B.Paste" user)
		(5 "F.SilkS" user "F.Silkscreen")
		(7 "B.SilkS" user "B.Silkscreen")
		(1 "F.Mask" user)
		(3 "B.Mask" user)
		(17 "Dwgs.User" user "User.Drawings")
		(19 "Cmts.User" user "User.Comments")
		(21 "Eco1.User" user "User.Eco1")
		(23 "Eco2.User" user "User.Eco2")
		(25 "Edge.Cuts" user)
		(27 "Margin" user)
		(31 "F.CrtYd" user "F.Courtyard")
		(29 "B.CrtYd" user "B.Courtyard")
		(35 "F.Fab" user)
		(33 "B.Fab" user)
	)
	(footprint "antmicro-footprints:C_0402_1005Metric"
		(layer "F.Cu")
		(at 184.039468 144.05 -90)
		(descr "Capacitor SMD 0402")
		(tags "capacitor SMD 0402")
		(property "Reference" "C218"
			(at 0.95 0.339468 90)
			(layer "F.SilkS")
			(effects
				(font
					(size 0.7 0.7)
					(thickness 0.15)
				)
				(justify right top)
			)
		)
		(property "Value" "C_4u7_25V_0402"
			(at -1.022927 2.155213 90)
			(layer "F.Fab")
			(effects
				(font
					(size 0.7 0.7)
					(thickness 0.15)
				)
				(justify right top)
			)
		)
		(property "Datasheet" "https://www.murata.com/products/productdetail?partno=GRM155C61E475ME15%23"
			(at 0 0 90)
			(layer "F.Fab")
			(hide yes)
			(effects
				(font
					(size 1.27 1.27)
					(thickness 0.15)
				)
			)
		)
		(property "Description" "SMD Multilayer Ceramic Capacitor"
			(at 0 0 90)
			(layer "F.Fab")
			(hide yes)
			(effects
				(font
					(size 1.27 1.27)
					(thickness 0.15)
				)
			)
		)
		(property "MPN" "GRM155C61E475ME15J"
			(at 0 0 270)
			(unlocked yes)
			(layer "F.Fab")
			(hide yes)
			(effects
				(font
					(size 1 1)
					(thickness 0.15)
				)
			)
		)
		(property "Manufacturer" "Murata"
			(at 0 0 270)
			(unlocked yes)
			(layer "F.Fab")
			(hide yes)
			(effects
				(font
					(size 1 1)
					(thickness 0.15)
				)
			)
		)
		(property "License" "Apache-2.0"
			(at 0 0 270)
			(unlocked yes)
			(layer "F.Fab")
			(hide yes)
			(effects
				(font
					(size 1 1)
					(thickness 0.15)
				)
			)
		)
		(property "Author" "Antmicro"
			(at 0 0 270)
			(unlocked yes)
			(layer "F.Fab")
			(hide yes)
			(effects
				(font
					(size 1 1)
					(thickness 0.15)
				)
			)
		)
		(property "Val" "4u7"
			(at 0 0 270)
			(unlocked yes)
			(layer "F.Fab")
			(hide yes)
			(effects
				(font
					(size 1 1)
					(thickness 0.15)
				)
			)
		)
		(property "Voltage" "25V"
			(at 0 0 270)
			(unlocked yes)
			(layer "F.Fab")
			(hide yes)
			(effects
				(font
					(size 1 1)
					(thickness 0.15)
				)
			)
		)
		(property "Dielectric" "X5S"
			(at 0 0 270)
			(unlocked yes)
			(layer "F.Fab")
			(hide yes)
			(effects
				(font
					(size 1 1)
					(thickness 0.15)
				)
			)
		)
		(sheetname "/DCDC/")
		(sheetfile "dcdc.kicad_sch")
		(attr smd)
		(fp_rect
			(start -0.925 -0.47)
			(end 0.925 0.47)
			(stroke
				(width 0.05)
				(type default)
			)
			(fill no)
			(layer "F.CrtYd")
		)
		(fp_line
			(start -0.494 0.248)
			(end -0.494 -0.25)
			(stroke
				(width 0.15)
				(type solid)
			)
			(layer "F.Fab")
		)
		(fp_line
			(start 0.504 0.248)
			(end -0.494 0.248)
			(stroke
				(width 0.15)
				(type solid)
			)
			(layer "F.Fab")
		)
		(fp_line
			(start -0.494 -0.25)
			(end 0.504 -0.25)
			(stroke
				(width 0.15)
				(type solid)
			)
			(layer "F.Fab")
		)
		(fp_line
			(start 0.504 -0.25)
			(end 0.504 0.248)
			(stroke
				(width 0.15)
				(type solid)
			)
			(layer "F.Fab")
		)
		(fp_text user "License: Apache-2.0"
			(at -0.939 5.799 90)
			(layer "F.Fab")
			(effects
				(font
					(size 0.7 0.7)
					(thickness 0.15)
				)
				(justify right top)
			)
		)
		(fp_text user "Author: Antmicro"
			(at -0.939 3.399 90)
			(layer "F.Fab")
			(effects
				(font
					(size 0.7 0.7)
					(thickness 0.15)
				)
				(justify right top)
			)
		)
		(fp_text user "${REFERENCE}"
			(at -0.939 4.599 90)
			(layer "F.Fab")
			(effects
				(font
					(size 0.7 0.7)
					(thickness 0.15)
				)
				(justify right top)
			)
		)
		(pad "1" smd roundrect
			(at -0.48 0 270)
			(size 0.59 0.64)
			(layers "F.Cu" "F.Mask" "F.Paste")
			(roundrect_rratio 0.25)
			(net 1 "GND")
			(pintype "passive")
		)
		(pad "2" smd roundrect
			(at 0.48 0 270)
			(size 0.59 0.64)
			(layers "F.Cu" "F.Mask" "F.Paste")
			(roundrect_rratio 0.25)
			(net 578 "/DCDC/12V_VDRV")
			(pintype "passive")
		)
	)
	(footprint "antmicro-footprints:C_0402_1005Metric"
		(layer "F.Cu")
		(at 147.634391 129.03)
		(descr "Capacitor SMD 0402")
		(tags "capacitor SMD 0402")
		(property "Reference" "C33"
			(at 0.965609 0.47 0)
			(layer "F.SilkS")
			(effects
				(font
					(size 0.7 0.7)
					(thickness 0.15)
				)
				(justify left bottom)
			)
		)
		(property "Value" "C_100n_0402"
			(at -1.022927 2.155213 0)
			(layer "F.Fab")
			(effects
				(font
					(size 0.7 0.7)
					(thickness 0.15)
				)
				(justify left bottom)
			)
		)
		(property "Datasheet" "https://www.murata.com/products/productdetail?partno=GRM155R61H104KE14%23"
			(at 0 0 0)
			(layer "F.Fab")
			(hide yes)
			(effects
				(font
					(size 1.27 1.27)
					(thickness 0.15)
				)
			)
		)
		(property "Description" "SMD Multilayer Ceramic Capacitor, 0.1 µF, 50 V, 0402 [1005 Metric], ± 10%, X5R, GRM Series"
			(at 0 0 0)
			(layer "F.Fab")
			(hide yes)
			(effects
				(font
					(size 1.27 1.27)
					(thickness 0.15)
				)
			)
		)
		(property "MPN" "GRM155R61H104KE14D"
			(at 0 0 0)
			(unlocked yes)
			(layer "F.Fab")
			(hide yes)
			(effects
				(font
					(size 1 1)
					(thickness 0.15)
				)
			)
		)
		(property "Manufacturer" "Murata"
			(at 0 0 0)
			(unlocked yes)
			(layer "F.Fab")
			(hide yes)
			(effects
				(font
					(size 1 1)
					(thickness 0.15)
				)
			)
		)
		(property "License" "Apache-2.0"
			(at 0 0 0)
			(unlocked yes)
			(layer "F.Fab")
			(hide yes)
			(effects
				(font
					(size 1 1)
					(thickness 0.15)
				)
			)
		)
		(property "Author" "Antmicro"
			(at 0 0 0)
			(unlocked yes)
			(layer "F.Fab")
			(hide yes)
			(effects
				(font
					(size 1 1)
					(thickness 0.15)
				)
			)
		)
		(property "Val" "100n"
			(at 0 0 0)
			(unlocked yes)
			(layer "F.Fab")
			(hide yes)
			(effects
				(font
					(size 1 1)
					(thickness 0.15)
				)
			)
		)
		(property "Voltage" "50V"
			(at 0 0 0)
			(unlocked yes)
			(layer "F.Fab")
			(hide yes)
			(effects
				(font
					(size 1 1)
					(thickness 0.15)
				)
			)
		)
		(property "Dielectric" "X5R"
			(at 0 0 0)
			(unlocked yes)
			(layer "F.Fab")
			(hide yes)
			(effects
				(font
					(size 1 1)
					(thickness 0.15)
				)
			)
		)
		(property "Public" "False"
			(at 0 0 0)
			(unlocked yes)
			(layer "F.Fab")
			(hide yes)
			(effects
				(font
					(size 1 1)
					(thickness 0.15)
				)
			)
		)
		(component_classes
			(class "DCDC_1V8")
		)
		(sheetname "/DCDC/")
		(sheetfile "dcdc.kicad_sch")
		(attr smd)
		(fp_rect
			(start -0.925 -0.47)
			(end 0.925 0.47)
			(stroke
				(width 0.05)
				(type default)
			)
			(fill no)
			(layer "F.CrtYd")
		)
		(fp_line
			(start -0.494 -0.25)
			(end 0.504 -0.25)
			(stroke
				(width 0.15)
				(type solid)
			)
			(layer "F.Fab")
		)
		(fp_line
			(start -0.494 0.248)
			(end -0.494 -0.25)
			(stroke
				(width 0.15)
				(type solid)
			)
			(layer "F.Fab")
		)
		(fp_line
			(start 0.504 -0.25)
			(end 0.504 0.248)
			(stroke
				(width 0.15)
				(type solid)
			)
			(layer "F.Fab")
		)
		(fp_line
			(start 0.504 0.248)
			(end -0.494 0.248)
			(stroke
				(width 0.15)
				(type solid)
			)
			(layer "F.Fab")
		)
		(fp_text user "${REFERENCE}"
			(at -0.939 4.599 0)
			(layer "F.Fab")
			(effects
				(font
					(size 0.7 0.7)
					(thickness 0.15)
				)
				(justify left bottom)
			)
		)
		(fp_text user "Author: Antmicro"
			(at -0.939 3.399 0)
			(layer "F.Fab")
			(effects
				(font
					(size 0.7 0.7)
					(thickness 0.15)
				)
				(justify left bottom)
			)
		)
		(fp_text user "License: Apache-2.0"
			(at -0.939 5.799 0)
			(layer "F.Fab")
			(effects
				(font
					(size 0.7 0.7)
					(thickness 0.15)
				)
				(justify left bottom)
			)
		)
		(pad "1" smd roundrect
			(at -0.48 0)
			(size 0.59 0.64)
			(layers "F.Cu" "F.Mask" "F.Paste")
			(roundrect_rratio 0.25)
			(net 1 "GND")
			(pintype "passive")
		)
		(pad "2" smd roundrect
			(at 0.48 0)
			(size 0.59 0.64)
			(layers "F.Cu" "F.Mask" "F.Paste")
			(roundrect_rratio 0.25)
			(net 17 "/DCDC/1V8_OUT")
			(pintype "passive")
		)
	)
	(footprint "antmicro-footprints:USON-10_2.5x1mm_P0.5mm"
		(layer "F.Cu")
		(at 221.402132 92.66 180)
		(descr "USON-10 2.5x1mm_ Pitch 0.5mm")
		(tags "USON-10 2.5x1mm Pitch 0.5mm")
		(property "Reference" "U41"
			(at -1.07 1.118 90)
			(layer "F.SilkS")
			(effects
				(font
					(size 0.7 0.7)
					(thickness 0.15)
				)
				(justify right top)
			)
		)
		(property "Value" "TPD4E05U06QDQARQ1"
			(at 0.018 2.499 0)
			(layer "F.Fab")
			(effects
				(font
					(size 0.7 0.7)
					(thickness 0.15)
				)
				(justify right top)
			)
		)
		(property "Datasheet" "https://www.ti.com/lit/ds/symlink/tpd4e05u06-q1.pdf?HQS=dis-mous-null-mousermode-dsf-pf-null-wwe&ts=1663591265741&ref_url=https%253A%252F%252Fwww.mouser.com%252F"
			(at 0 0 0)
			(layer "F.Fab")
			(hide yes)
			(effects
				(font
					(size 1.27 1.27)
					(thickness 0.15)
				)
			)
		)
		(property "Description" "TVS diode array, 12 kV, USON-10, 5.5 V, 0.5 pF"
			(at 0 0 0)
			(layer "F.Fab")
			(hide yes)
			(effects
				(font
					(size 1.27 1.27)
					(thickness 0.15)
				)
			)
		)
		(property "Manufacturer" "Texas Instruments"
			(at 0 0 180)
			(unlocked yes)
			(layer "F.Fab")
			(hide yes)
			(effects
				(font
					(size 1 1)
					(thickness 0.15)
				)
			)
		)
		(property "MPN" "TPD4E05U06QDQARQ1"
			(at 0 0 180)
			(unlocked yes)
			(layer "F.Fab")
			(hide yes)
			(effects
				(font
					(size 1 1)
					(thickness 0.15)
				)
			)
		)
		(property "Author" "Antmicro"
			(at 0 0 180)
			(unlocked yes)
			(layer "F.Fab")
			(hide yes)
			(effects
				(font
					(size 1 1)
					(thickness 0.15)
				)
			)
		)
		(property "License" "Apache-2.0"
			(at 0 0 180)
			(unlocked yes)
			(layer "F.Fab")
			(hide yes)
			(effects
				(font
					(size 1 1)
					(thickness 0.15)
				)
			)
		)
		(sheetname "/USB DP Alt mode/")
		(sheetfile "usb_dp.kicad_sch")
		(attr smd)
		(fp_line
			(start 0.498 1.398)
			(end -0.5 1.398)
			(stroke
				(width 0.15)
				(type solid)
			)
			(layer "F.SilkS")
		)
		(fp_line
			(start 0.498 -1.401)
			(end -0.5 -1.401)
			(stroke
				(width 0.15)
				(type solid)
			)
			(layer "F.SilkS")
		)
		(fp_circle
			(center -0.68 -1.27)
			(end -0.63 -1.27)
			(stroke
				(width 0.15)
				(type solid)
			)
			(fill yes)
			(layer "F.SilkS")
		)
		(fp_rect
			(start -0.8 -1.5)
			(end 0.8 1.499)
			(stroke
				(width 0.05)
				(type solid)
			)
			(fill no)
			(layer "F.CrtYd")
		)
		(fp_line
			(start 0.498 -1.25)
			(end 0.498 1.249)
			(stroke
				(width 0.15)
				(type solid)
			)
			(layer "F.Fab")
		)
		(fp_line
			(start 0.498 -1.25)
			(end -0.25 -1.25)
			(stroke
				(width 0.15)
				(type solid)
			)
			(layer "F.Fab")
		)
		(fp_line
			(start -0.25 -1.25)
			(end -0.5 -1)
			(stroke
				(width 0.15)
				(type solid)
			)
			(layer "F.Fab")
		)
		(fp_line
			(start -0.5 1.249)
			(end 0.498 1.249)
			(stroke
				(width 0.15)
				(type solid)
			)
			(layer "F.Fab")
		)
		(fp_line
			(start -0.5 -1)
			(end -0.5 1.249)
			(stroke
				(width 0.15)
				(type solid)
			)
			(layer "F.Fab")
		)
		(fp_text user "License: Apache-2.0"
			(at -0.802 6.9 0)
			(layer "F.Fab")
			(effects
				(font
					(size 0.7 0.7)
					(thickness 0.15)
				)
				(justify right top)
			)
		)
		(fp_text user "${REFERENCE}"
			(at -0.802 4.498 0)
			(layer "F.Fab")
			(effects
				(font
					(size 0.7 0.7)
					(thickness 0.15)
				)
				(justify right top)
			)
		)
		(fp_text user "Author: Antmicro"
			(at -0.802 5.7 0)
			(layer "F.Fab")
			(effects
				(font
					(size 0.7 0.7)
					(thickness 0.15)
				)
				(justify right top)
			)
		)
		(pad "1" smd roundrect
			(at -0.387 -1 90)
			(size 0.25 0.55)
			(layers "F.Cu" "F.Mask" "F.Paste")
			(roundrect_rratio 0.25)
			(net 822 "/USB DP Alt mode/USBC1_RX1_P")
			(pintype "passive")
		)
		(pad "2" smd roundrect
			(at -0.387 -0.5 90)
			(size 0.25 0.55)
			(layers "F.Cu" "F.Mask" "F.Paste")
			(roundrect_rratio 0.25)
			(net 819 "/USB DP Alt mode/USBC1_RX1_N")
			(pintype "passive")
		)
		(pad "3" smd roundrect
			(at -0.387 0 90)
			(size 0.4 0.55)
			(layers "F.Cu" "F.Mask" "F.Paste")
			(roundrect_rratio 0.25)
			(net 1 "GND")
			(pintype "power_in")
		)
		(pad "4" smd roundrect
			(at -0.387 0.498 90)
			(size 0.25 0.55)
			(layers "F.Cu" "F.Mask" "F.Paste")
			(roundrect_rratio 0.25)
			(net 345 "/USB DP Alt mode/USBC1_CONN_TX1_P")
			(pintype "passive")
		)
		(pad "5" smd roundrect
			(at -0.387 0.998 90)
			(size 0.25 0.55)
			(layers "F.Cu" "F.Mask" "F.Paste")
			(roundrect_rratio 0.25)
			(net 361 "/USB DP Alt mode/USBC1_CONN_TX1_N")
			(pintype "passive")
		)
		(pad "6" smd roundrect
			(at 0.385 0.998 90)
			(size 0.25 0.55)
			(layers "F.Cu" "F.Mask" "F.Paste")
			(roundrect_rratio 0.25)
			(net 361 "/USB DP Alt mode/USBC1_CONN_TX1_N")
			(pintype "passive")
		)
		(pad "7" smd roundrect
			(at 0.385 0.498 90)
			(size 0.25 0.55)
			(layers "F.Cu" "F.Mask" "F.Paste")
			(roundrect_rratio 0.25)
			(net 345 "/USB DP Alt mode/USBC1_CONN_TX1_P")
			(pintype "passive")
		)
		(pad "8" smd roundrect
			(at 0.385 0 90)
			(size 0.4 0.55)
			(layers "F.Cu" "F.Mask" "F.Paste")
			(roundrect_rratio 0.25)
			(net 1 "GND")
			(pintype "passive")
		)
		(pad "9" smd roundrect
			(at 0.385 -0.5 90)
			(size 0.25 0.55)
			(layers "F.Cu" "F.Mask" "F.Paste")
			(roundrect_rratio 0.25)
			(net 819 "/USB DP Alt mode/USBC1_RX1_N")
			(pintype "passive")
		)
		(pad "10" smd roundrect
			(at 0.385 -1 90)
			(size 0.25 0.55)
			(layers "F.Cu" "F.Mask" "F.Paste")
			(roundrect_rratio 0.25)
			(net 822 "/USB DP Alt mode/USBC1_RX1_P")
			(pintype "passive")
		)
	)
	(footprint "antmicro-footprints:C_0805_2012Metric"
		(layer "F.Cu")
		(at 176.33 146.32 -90)
		(descr "Capacitor SMD 0805")
		(tags "capacitor SMD 0805")
		(property "Reference" "C222"
			(at 1.88 0.25 90)
			(layer "F.SilkS")
			(effects
				(font
					(size 0.7 0.7)
					(thickness 0.15)
				)
				(justify right top)
			)
		)
		(property "Value" "C_22u_25V_0805"
			(at -2.055717 1.963152 90)
			(layer "F.Fab")
			(effects
				(font
					(size 0.7 0.7)
					(thickness 0.15)
				)
				(justify right top)
			)
		)
		(property "Datasheet" "https://product.samsungsem.com/mlcc/CL21A226MAYNNN.do"
			(at 0 0 90)
			(layer "F.Fab")
			(hide yes)
			(effects
				(font
					(size 1.27 1.27)
					(thickness 0.15)
				)
			)
		)
		(property "Description" "SMT Multilayer Ceramic Capacitor, 22uF, +/-20%, 25V, X5R, 0805 [2012 Metric]"
			(at 0 0 90)
			(layer "F.Fab")
			(hide yes)
			(effects
				(font
					(size 1.27 1.27)
					(thickness 0.15)
				)
			)
		)
		(property "Manufacturer" "Samsung Electro-Mechanics"
			(at 0 0 270)
			(unlocked yes)
			(layer "F.Fab")
			(hide yes)
			(effects
				(font
					(size 1 1)
					(thickness 0.15)
				)
			)
		)
		(property "MPN" "CL21A226MAYNNNE"
			(at 0 0 270)
			(unlocked yes)
			(layer "F.Fab")
			(hide yes)
			(effects
				(font
					(size 1 1)
					(thickness 0.15)
				)
			)
		)
		(property "Val" "22u"
			(at 0 0 270)
			(unlocked yes)
			(layer "F.Fab")
			(hide yes)
			(effects
				(font
					(size 1 1)
					(thickness 0.15)
				)
			)
		)
		(property "License" "Apache-2.0"
			(at 0 0 270)
			(unlocked yes)
			(layer "F.Fab")
			(hide yes)
			(effects
				(font
					(size 1 1)
					(thickness 0.15)
				)
			)
		)
		(property "Author" "Antmicro"
			(at 0 0 270)
			(unlocked yes)
			(layer "F.Fab")
			(hide yes)
			(effects
				(font
					(size 1 1)
					(thickness 0.15)
				)
			)
		)
		(property "Voltage" "25V"
			(at 0 0 270)
			(unlocked yes)
			(layer "F.Fab")
			(hide yes)
			(effects
				(font
					(size 1 1)
					(thickness 0.15)
				)
			)
		)
		(property "Dielectric" "X5R"
			(at 0 0 270)
			(unlocked yes)
			(layer "F.Fab")
			(hide yes)
			(effects
				(font
					(size 1 1)
					(thickness 0.15)
				)
			)
		)
		(property "Public" "False"
			(at 0 0 270)
			(unlocked yes)
			(layer "F.Fab")
			(hide yes)
			(effects
				(font
					(size 1 1)
					(thickness 0.15)
				)
			)
		)
		(sheetname "/DCDC/")
		(sheetfile "dcdc.kicad_sch")
		(attr smd)
		(fp_line
			(start -0.3 0.7)
			(end 0.3 0.7)
			(stroke
				(width 0.15)
				(type solid)
			)
			(layer "F.SilkS")
		)
		(fp_line
			(start -0.3 -0.7)
			(end 0.3 -0.7)
			(stroke
				(width 0.15)
				(type solid)
			)
			(layer "F.SilkS")
		)
		(fp_rect
			(start 1.95 -0.9)
			(end -1.95 0.9)
			(stroke
				(width 0.05)
				(type default)
			)
			(fill no)
			(layer "F.CrtYd")
		)
		(fp_rect
			(start -0.95 -0.675)
			(end 0.95 0.675)
			(stroke
				(width 0.15)
				(type solid)
			)
			(fill no)
			(layer "F.Fab")
		)
		(fp_text user "Author: Antmicro"
			(at -1.9 5.947 90)
			(layer "F.Fab")
			(effects
				(font
					(size 0.7 0.7)
					(thickness 0.15)
				)
				(justify right top)
			)
		)
		(fp_text user "${REFERENCE}"
			(at -1.9 3.947 90)
			(layer "F.Fab")
			(effects
				(font
					(size 0.7 0.7)
					(thickness 0.15)
				)
				(justify right top)
			)
		)
		(fp_text user "License: Apache-2.0"
			(at -1.9 4.947 90)
			(layer "F.Fab")
			(effects
				(font
					(size 0.7 0.7)
					(thickness 0.15)
				)
				(justify right top)
			)
		)
		(pad "1" smd roundrect
			(at -1.1 0 270)
			(size 1.2 1.3)
			(layers "F.Cu" "F.Mask" "F.Paste")
			(roundrect_rratio 0.25)
			(net 1 "GND")
			(pintype "passive")
		)
		(pad "2" smd roundrect
			(at 1.1 0 270)
			(size 1.2 1.3)
			(layers "F.Cu" "F.Mask" "F.Paste")
			(roundrect_rratio 0.25)
			(net 880 "/DCDC/12V_OUT")
			(pintype "passive")
		)
	)
)
